# SCM (Grand Teton) — schematic netlist excerpt (pin names and nets, part order shuffled) for the footprints in the layout excerpt that follows; sources: Cadence DE-HDL packaged netlist, KiCad conversion of 12092022_DA0F0TMDCD0_F0T_Management_Board_D_brd_V3_OCP.brd

R713  Q_RES  33.2 1% CHIP  pkg 0402LF  page 17 : A = LPC_ESPI_SEL_R ; B = LPC_ESPI_SEL
R176  Q_RES  33.2 1% CHIP  pkg 0402LF  page 44 : A = SPI_BMC_BIOS_ROM_MISO ; B = SPI_BMC_BIOS_ROM_R_MISO

(kicad_pcb
	(version 20260206)
	(generator "pcbnew")
	(generator_version "10.0")
	(general
		(thickness 1.6)
		(legacy_teardrops no)
	)
	(paper "A4")
	(title_block
		(title "12092022_DA0F0TMDCD0_F0T_Management_Board_D_brd_V3_OCP.brd")
		(comment 1 "Grand Teton / footprints 1265-1266 of 1440")
	)
	(layers
		(0 "F.Cu" signal "TOP")
		(4 "In1.Cu" signal "GND")
		(6 "In2.Cu" signal "IN1")
		(8 "In3.Cu" signal "GND1")
		(10 "In4.Cu" signal "IN2")
		(12 "In5.Cu" signal "VCC")
		(14 "In6.Cu" signal "VCC1")
		(16 "In7.Cu" signal "IN3")
		(18 "In8.Cu" signal "GND2")
		(20 "In9.Cu" signal "IN4")
		(22 "In10.Cu" signal "GND3")
		(2 "B.Cu" signal "BOTTOM")
		(9 "F.Adhes" user "F.Adhesive")
		(11 "B.Adhes" user "B.Adhesive")
		(13 "F.Paste" user "Package Geometry/Pastemask Top")
		(15 "B.Paste" user "Package Geometry/Pastemask Bottom")
		(5 "F.SilkS" user "Ref Des/Silkscreen Top")
		(7 "B.SilkS" user "Ref Des/Silkscreen Bottom")
		(1 "F.Mask" user "Board Geometry/Soldermask Top")
		(3 "B.Mask" user "Board Geometry/Soldermask Bottom")
		(17 "Dwgs.User" user "User.Drawings")
		(19 "Cmts.User" user "User.Comments")
		(21 "Eco1.User" user "User.Eco1")
		(23 "Eco2.User" user "User.Eco2")
		(25 "Edge.Cuts" user "Board Geometry/Outline")
		(27 "Margin" user)
		(31 "F.CrtYd" user "Package Geometry/Place Bound Top")
		(29 "B.CrtYd" user "Package Geometry/Place Bound Bottom")
		(35 "F.Fab" user "Ref Des/Assembly Top")
		(33 "B.Fab" user "Ref Des/Assembly Bottom")
	)
	(footprint ""
		(layer "B.Cu")
		(at 59.7154 -64.3382 -90)
		(property "Reference" "R176"
			(at 0 0 90)
			(layer "B.SilkS")
			(hide yes)
			(effects
				(font
					(size 1.27 1.27)
				)
				(justify mirror)
			)
		)
		(property "Value" ""
			(at 0 0 90)
			(layer "B.Fab")
			(effects
				(font
					(size 1.27 1.27)
				)
				(justify mirror)
			)
		)
		(duplicate_pad_numbers_are_jumpers no)
		(fp_line
			(start -0.7874 0.4064)
			(end 0.7874 0.4064)
			(stroke
				(width 0.1524)
				(type default)
			)
			(layer "B.SilkS")
		)
		(fp_line
			(start 0.7874 0.4064)
			(end 0.7874 -0.4064)
			(stroke
				(width 0.1524)
				(type default)
			)
			(layer "B.SilkS")
		)
		(fp_line
			(start -0.7874 -0.4064)
			(end -0.7874 0.4064)
			(stroke
				(width 0.1524)
				(type default)
			)
			(layer "B.SilkS")
		)
		(fp_line
			(start 0.7874 -0.4064)
			(end -0.7874 -0.4064)
			(stroke
				(width 0.1524)
				(type default)
			)
			(layer "B.SilkS")
		)
		(fp_line
			(start -0.67945 0.3048)
			(end -0.120396 0.3048)
			(stroke
				(width 0.1)
				(type default)
			)
			(layer "B.Fab")
		)
		(fp_line
			(start -0.120396 0.3048)
			(end -0.120396 0.2794)
			(stroke
				(width 0.1)
				(type default)
			)
			(layer "B.Fab")
		)
		(fp_line
			(start 0.12065 0.3048)
			(end 0.67945 0.3048)
			(stroke
				(width 0.1)
				(type default)
			)
			(layer "B.Fab")
		)
		(fp_line
			(start 0.67945 0.3048)
			(end 0.67945 -0.305054)
			(stroke
				(width 0.1)
				(type default)
			)
			(layer "B.Fab")
		)
		(fp_line
			(start -0.120396 0.2794)
			(end 0.12065 0.2794)
			(stroke
				(width 0.1)
				(type default)
			)
			(layer "B.Fab")
		)
		(fp_line
			(start 0.12065 0.2794)
			(end 0.12065 0.3048)
			(stroke
				(width 0.1)
				(type default)
			)
			(layer "B.Fab")
		)
		(fp_line
			(start -0.12065 -0.2794)
			(end -0.12065 -0.3048)
			(stroke
				(width 0.1)
				(type default)
			)
			(layer "B.Fab")
		)
		(fp_line
			(start 0.12065 -0.2794)
			(end -0.12065 -0.2794)
			(stroke
				(width 0.1)
				(type default)
			)
			(layer "B.Fab")
		)
		(fp_line
			(start -0.67945 -0.3048)
			(end -0.67945 0.3048)
			(stroke
				(width 0.1)
				(type default)
			)
			(layer "B.Fab")
		)
		(fp_line
			(start -0.12065 -0.3048)
			(end -0.67945 -0.3048)
			(stroke
				(width 0.1)
				(type default)
			)
			(layer "B.Fab")
		)
		(fp_line
			(start 0.12065 -0.305054)
			(end 0.12065 -0.2794)
			(stroke
				(width 0.1)
				(type default)
			)
			(layer "B.Fab")
		)
		(fp_line
			(start 0.67945 -0.305054)
			(end 0.12065 -0.305054)
			(stroke
				(width 0.1)
				(type default)
			)
			(layer "B.Fab")
		)
		(pad "1" smd circle
			(at 0.40005 0 90)
			(size 0 0)
			(layers "B.Cu" "B.Mask" "B.Paste")
			(net "SPI_BMC_BIOS_ROM_MISO")
		)
		(pad "2" smd circle
			(at -0.40005 0 90)
			(size 0 0)
			(layers "B.Cu" "B.Mask" "B.Paste")
			(net "SPI_BMC_BIOS_ROM_R_MISO")
		)
	)
	(footprint ""
		(layer "B.Cu")
		(at 77.2795 -99.911408)
		(property "Reference" "R713"
			(at 0 0 0)
			(layer "B.SilkS")
			(hide yes)
			(effects
				(font
					(size 1.27 1.27)
				)
				(justify mirror)
			)
		)
		(property "Value" ""
			(at 0 0 0)
			(layer "B.Fab")
			(effects
				(font
					(size 1.27 1.27)
				)
				(justify mirror)
			)
		)
		(duplicate_pad_numbers_are_jumpers no)
		(fp_line
			(start -0.7874 -0.4064)
			(end -0.7874 0.4064)
			(stroke
				(width 0.1524)
				(type default)
			)
			(layer "B.SilkS")
		)
		(fp_line
			(start -0.7874 0.4064)
			(end 0.7874 0.4064)
			(stroke
				(width 0.1524)
				(type default)
			)
			(layer "B.SilkS")
		)
		(fp_line
			(start 0.7874 -0.4064)
			(end -0.7874 -0.4064)
			(stroke
				(width 0.1524)
				(type default)
			)
			(layer "B.SilkS")
		)
		(fp_line
			(start 0.7874 0.4064)
			(end 0.7874 -0.4064)
			(stroke
				(width 0.1524)
				(type default)
			)
			(layer "B.SilkS")
		)
		(fp_line
			(start -0.67945 -0.3048)
			(end -0.67945 0.3048)
			(stroke
				(width 0.1)
				(type default)
			)
			(layer "B.Fab")
		)
		(fp_line
			(start -0.67945 0.3048)
			(end -0.120396 0.3048)
			(stroke
				(width 0.1)
				(type default)
			)
			(layer "B.Fab")
		)
		(fp_line
			(start -0.12065 -0.3048)
			(end -0.67945 -0.3048)
			(stroke
				(width 0.1)
				(type default)
			)
			(layer "B.Fab")
		)
		(fp_line
			(start -0.12065 -0.2794)
			(end -0.12065 -0.3048)
			(stroke
				(width 0.1)
				(type default)
			)
			(layer "B.Fab")
		)
		(fp_line
			(start -0.120396 0.2794)
			(end 0.12065 0.2794)
			(stroke
				(width 0.1)
				(type default)
			)
			(layer "B.Fab")
		)
		(fp_line
			(start -0.120396 0.3048)
			(end -0.120396 0.2794)
			(stroke
				(width 0.1)
				(type default)
			)
			(layer "B.Fab")
		)
		(fp_line
			(start 0.12065 -0.305054)
			(end 0.12065 -0.2794)
			(stroke
				(width 0.1)
				(type default)
			)
			(layer "B.Fab")
		)
		(fp_line
			(start 0.12065 -0.2794)
			(end -0.12065 -0.2794)
			(stroke
				(width 0.1)
				(type default)
			)
			(layer "B.Fab")
		)
		(fp_line
			(start 0.12065 0.2794)
			(end 0.12065 0.3048)
			(stroke
				(width 0.1)
				(type default)
			)
			(layer "B.Fab")
		)
		(fp_line
			(start 0.12065 0.3048)
			(end 0.67945 0.3048)
			(stroke
				(width 0.1)
				(type default)
			)
			(layer "B.Fab")
		)
		(fp_line
			(start 0.67945 -0.305054)
			(end 0.12065 -0.305054)
			(stroke
				(width 0.1)
				(type default)
			)
			(layer "B.Fab")
		)
		(fp_line
			(start 0.67945 0.3048)
			(end 0.67945 -0.305054)
			(stroke
				(width 0.1)
				(type default)
			)
			(layer "B.Fab")
		)
		(pad "1" smd circle
			(at 0.40005 0 180)
			(size 0 0)
			(layers "B.Cu" "B.Mask" "B.Paste")
			(net "LPC_ESPI_SEL_R")
		)
		(pad "2" smd circle
			(at -0.40005 0 180)
			(size 0 0)
			(layers "B.Cu" "B.Mask" "B.Paste")
			(net "LPC_ESPI_SEL")
		)
	)
)
